(kicad_pcb
	(version 20241229)
	(generator "pcbnew")
	(generator_version "9.0")
	(general
		(thickness 1.6)
		(legacy_teardrops no)
	)
	(paper "A4")
	(title_block
		(title "OCuLink to PCIe adapter")
		(date "2025-06-18")
		(rev "1.0.0")
		(company "Antmicro Ltd")
		(comment 1 "www.antmicro.com")
		(comment 9 "footprints 41-43 of 159")
	)
	(layers
		(0 "F.Cu" signal)
		(4 "In1.Cu" signal)
		(6 "In2.Cu" signal)
		(2 "B.Cu" signal)
		(9 "F.Adhes" user "F.Adhesive")
		(11 "B.Adhes" user "B.Adhesive")
		(13 "F.Paste" user)
		(15 "B.Paste" user)
		(5 "F.SilkS" user "F.Silkscreen")
		(7 "B.SilkS" user "B.Silkscreen")
		(1 "F.Mask" user)
		(3 "B.Mask" user)
		(17 "Dwgs.User" user "User.Drawings")
		(19 "Cmts.User" user "User.Comments")
		(21 "Eco1.User" user "User.Eco1")
		(23 "Eco2.User" user "User.Eco2")
		(25 "Edge.Cuts" user)
		(27 "Margin" user)
		(31 "F.CrtYd" user "F.Courtyard")
		(29 "B.CrtYd" user "B.Courtyard")
		(35 "F.Fab" user)
		(33 "B.Fab" user)
	)
	(footprint "antmicro-footprints:USB-C_Receptacle_GCT_USB4105-GF-A"
		(locked yes)
		(layer "F.Cu")
		(at 144.2 35 180)
		(property "Reference" "J3"
			(at -1.6 -5.4 180)
			(layer "F.SilkS")
			(effects
				(font
					(size 0.7 0.7)
					(thickness 0.15)
				)
				(justify left bottom)
			)
		)
		(property "Value" "USB-C_GCT_USB4105-GF-A"
			(at 0 5 0)
			(layer "F.Fab")
			(effects
				(font
					(size 0.7 0.7)
					(thickness 0.15)
				)
				(justify right top)
			)
		)
		(property "Datasheet" "https://gct.co/files/drawings/usb4105.pdf"
			(at 0 0 0)
			(layer "F.Fab")
			(hide yes)
			(effects
				(font
					(size 1.27 1.27)
					(thickness 0.15)
				)
			)
		)
		(property "Description" "USB-C (USB TYPE-C) USB 2.0 Receptacle Connector 24 (16+8 Dummy) Position Surface Mount, Right Angle"
			(at 0 0 0)
			(layer "F.Fab")
			(hide yes)
			(effects
				(font
					(size 1.27 1.27)
					(thickness 0.15)
				)
			)
		)
		(property "Manufacturer" "GCT"
			(at 0 0 180)
			(unlocked yes)
			(layer "F.Fab")
			(hide yes)
			(effects
				(font
					(size 1 1)
					(thickness 0.15)
				)
			)
		)
		(property "MPN" "USB4105-GF-A"
			(at 0 0 180)
			(unlocked yes)
			(layer "F.Fab")
			(hide yes)
			(effects
				(font
					(size 1 1)
					(thickness 0.15)
				)
			)
		)
		(property "Author" "Antmicro"
			(at 0 0 180)
			(unlocked yes)
			(layer "F.Fab")
			(hide yes)
			(effects
				(font
					(size 1 1)
					(thickness 0.15)
				)
			)
		)
		(property "License" "Apache-2.0"
			(at 0 0 180)
			(unlocked yes)
			(layer "F.Fab")
			(hide yes)
			(effects
				(font
					(size 1 1)
					(thickness 0.15)
				)
			)
		)
		(sheetname "/USB-PD/")
		(sheetfile "usb-pd.kicad_sch")
		(attr smd)
		(fp_line
			(start 4.788 3.854)
			(end 4.788 2.575)
			(stroke
				(width 0.15)
				(type solid)
			)
			(layer "F.SilkS")
		)
		(fp_line
			(start 4.788 -1.395)
			(end 4.788 -0.145)
			(stroke
				(width 0.15)
				(type solid)
			)
			(layer "F.SilkS")
		)
		(fp_line
			(start -4.79 3.854)
			(end 4.788 3.854)
			(stroke
				(width 0.15)
				(type solid)
			)
			(layer "F.SilkS")
		)
		(fp_line
			(start -4.79 2.575)
			(end -4.79 3.854)
			(stroke
				(width 0.15)
				(type solid)
			)
			(layer "F.SilkS")
		)
		(fp_line
			(start -4.79 -1.395)
			(end -4.79 -0.145)
			(stroke
				(width 0.15)
				(type solid)
			)
			(layer "F.SilkS")
		)
		(fp_circle
			(center -3.8 -4.27071)
			(end -3.75 -4.22071)
			(stroke
				(width 0.15)
				(type solid)
			)
			(fill yes)
			(layer "F.SilkS")
		)
		(fp_rect
			(start -5.1 -4.4)
			(end 5.1 3.9)
			(stroke
				(width 0.05)
				(type solid)
			)
			(fill no)
			(layer "F.CrtYd")
		)
		(fp_line
			(start 4.788 3.854)
			(end -4.79 3.854)
			(stroke
				(width 0.15)
				(type solid)
			)
			(layer "F.Fab")
		)
		(fp_line
			(start 4.788 -3.676)
			(end 4.788 3.854)
			(stroke
				(width 0.15)
				(type solid)
			)
			(layer "F.Fab")
		)
		(fp_line
			(start -4.702 3.854)
			(end 4.788 3.854)
			(stroke
				(width 0.15)
				(type solid)
			)
			(layer "F.Fab")
		)
		(fp_line
			(start -4.79 3.854)
			(end -4.79 -3.676)
			(stroke
				(width 0.15)
				(type solid)
			)
			(layer "F.Fab")
		)
		(fp_line
			(start -4.79 -3.676)
			(end 4.788 -3.676)
			(stroke
				(width 0.15)
				(type solid)
			)
			(layer "F.Fab")
		)
		(fp_text user "Author: Antmicro"
			(at -4.79 7.853 0)
			(layer "F.Fab")
			(effects
				(font
					(size 0.7 0.7)
					(thickness 0.15)
				)
				(justify right top)
			)
		)
		(fp_text user "License: Apache-2.0"
			(at -4.79 8.855 0)
			(layer "F.Fab")
			(effects
				(font
					(size 0.7 0.7)
					(thickness 0.15)
				)
				(justify right top)
			)
		)
		(fp_text user "${REFERENCE}"
			(at 0 -0.247999 180)
			(layer "F.Fab")
			(effects
				(font
					(size 0.7 0.7)
					(thickness 0.15)
				)
				(justify left bottom)
			)
		)
		(fp_text user "PCB-EDGE"
			(at -4.789999 5.853 0)
			(layer "F.Fab")
			(effects
				(font
					(size 0.7 0.7)
					(thickness 0.15)
				)
				(justify right top)
			)
		)
		(pad "" np_thru_hole circle
			(at -2.891 -2.426 180)
			(size 0.65 0.65)
			(drill 0.65)
			(layers "*.Cu" "*.Mask")
		)
		(pad "" np_thru_hole circle
			(at 2.89 -2.426 180)
			(size 0.65 0.65)
			(drill 0.65)
			(layers "*.Cu" "*.Mask")
		)
		(pad "A1" smd roundrect
			(at -3.202 -3.5 180)
			(size 0.6 1.15)
			(layers "F.Cu" "F.Mask" "F.Paste")
			(roundrect_rratio 0.25)
			(net 66 "GND")
			(pinfunction "GND")
			(pintype "power_in")
		)
		(pad "A4" smd roundrect
			(at -2.4 -3.5 180)
			(size 0.6 1.15)
			(layers "F.Cu" "F.Mask" "F.Paste")
			(roundrect_rratio 0.25)
			(net 113 "VBUS")
			(pinfunction "VBUS")
			(pintype "passive")
		)
		(pad "A5" smd roundrect
			(at -1.25 -3.5 180)
			(size 0.3 1.15)
			(layers "F.Cu" "F.Mask" "F.Paste")
			(roundrect_rratio 0.25)
			(net 140 "/USB-PD/CC1")
			(pinfunction "CC_{1}")
			(pintype "bidirectional")
		)
		(pad "A6" smd roundrect
			(at -0.25 -3.5 180)
			(size 0.3 1.15)
			(layers "F.Cu" "F.Mask" "F.Paste")
			(roundrect_rratio 0.25)
			(net 128 "unconnected-(J3-D_{A}+-PadA6)")
			(pinfunction "D_{A}+")
			(pintype "bidirectional+no_connect")
		)
		(pad "A7" smd roundrect
			(at 0.248 -3.5 180)
			(size 0.3 1.15)
			(layers "F.Cu" "F.Mask" "F.Paste")
			(roundrect_rratio 0.25)
			(net 126 "unconnected-(J3-D_{A}--PadA7)")
			(pinfunction "D_{A}-")
			(pintype "bidirectional+no_connect")
		)
		(pad "A8" smd roundrect
			(at 1.249 -3.5 180)
			(size 0.3 1.15)
			(layers "F.Cu" "F.Mask" "F.Paste")
			(roundrect_rratio 0.25)
			(net 130 "unconnected-(J3-SBU_{1}-PadA8)")
			(pinfunction "SBU_{1}")
			(pintype "bidirectional+no_connect")
		)
		(pad "A9" smd roundrect
			(at 2.398 -3.5 180)
			(size 0.6 1.15)
			(layers "F.Cu" "F.Mask" "F.Paste")
			(roundrect_rratio 0.25)
			(net 113 "VBUS")
			(pinfunction "VBUS")
			(pintype "passive")
		)
		(pad "A12" smd roundrect
			(at 3.2 -3.5 180)
			(size 0.6 1.15)
			(layers "F.Cu" "F.Mask" "F.Paste")
			(roundrect_rratio 0.25)
			(net 66 "GND")
			(pinfunction "GND")
			(pintype "passive")
		)
		(pad "B1" smd roundrect
			(at 3.2 -3.5 180)
			(size 0.6 1.15)
			(layers "F.Cu" "F.Mask" "F.Paste")
			(roundrect_rratio 0.25)
			(net 66 "GND")
			(pinfunction "GND")
			(pintype "passive")
		)
		(pad "B4" smd roundrect
			(at 2.398 -3.5 180)
			(size 0.6 1.15)
			(layers "F.Cu" "F.Mask" "F.Paste")
			(roundrect_rratio 0.25)
			(net 113 "VBUS")
			(pinfunction "VBUS")
			(pintype "passive")
		)
		(pad "B5" smd roundrect
			(at 1.749 -3.5 180)
			(size 0.3 1.15)
			(layers "F.Cu" "F.Mask" "F.Paste")
			(roundrect_rratio 0.25)
			(net 139 "/USB-PD/CC2")
			(pinfunction "CC_{2}")
			(pintype "bidirectional")
		)
		(pad "B6" smd roundrect
			(at 0.748 -3.5 180)
			(size 0.3 1.15)
			(layers "F.Cu" "F.Mask" "F.Paste")
			(roundrect_rratio 0.25)
			(net 127 "unconnected-(J3-D_{B}+-PadB6)")
			(pinfunction "D_{B}+")
			(pintype "bidirectional+no_connect")
		)
		(pad "B7" smd roundrect
			(at -0.75 -3.5 180)
			(size 0.3 1.15)
			(layers "F.Cu" "F.Mask" "F.Paste")
			(roundrect_rratio 0.25)
			(net 129 "unconnected-(J3-D_{B}--PadB7)")
			(pinfunction "D_{B}-")
			(pintype "bidirectional+no_connect")
		)
		(pad "B8" smd roundrect
			(at -1.75 -3.5 180)
			(size 0.3 1.15)
			(layers "F.Cu" "F.Mask" "F.Paste")
			(roundrect_rratio 0.25)
			(net 131 "unconnected-(J3-SBU_{2}-PadB8)")
			(pinfunction "SBU_{2}")
			(pintype "bidirectional+no_connect")
		)
		(pad "B9" smd roundrect
			(at -2.4 -3.5 180)
			(size 0.6 1.15)
			(layers "F.Cu" "F.Mask" "F.Paste")
			(roundrect_rratio 0.25)
			(net 113 "VBUS")
			(pinfunction "VBUS")
			(pintype "passive")
		)
		(pad "B12" smd roundrect
			(at -3.202 -3.5 180)
			(size 0.6 1.15)
			(layers "F.Cu" "F.Mask" "F.Paste")
			(roundrect_rratio 0.25)
			(net 66 "GND")
			(pinfunction "GND")
			(pintype "passive")
		)
		(pad "SH" thru_hole oval
			(at -4.321 -2.926 180)
			(size 1.05 2.1)
			(drill oval 0.6 1.7)
			(layers "*.Cu" "*.Mask")
			(remove_unused_layers no)
			(net 66 "GND")
			(pinfunction "SH")
			(pintype "passive")
		)
		(pad "SH" thru_hole oval
			(at -4.321 1.255 180)
			(size 1 2)
			(drill oval 0.6 1.4)
			(layers "*.Cu" "*.Mask")
			(remove_unused_layers no)
			(net 66 "GND")
			(pinfunction "SH")
			(pintype "passive")
		)
		(pad "SH" thru_hole oval
			(at 4.32 -2.926 180)
			(size 1.05 2.1)
			(drill oval 0.6 1.7)
			(layers "*.Cu" "*.Mask")
			(remove_unused_layers no)
			(net 66 "GND")
			(pinfunction "SH")
			(pintype "passive")
		)
		(pad "SH" thru_hole oval
			(at 4.32 1.255 180)
			(size 1 2)
			(drill oval 0.6 1.4)
			(layers "*.Cu" "*.Mask")
			(remove_unused_layers no)
			(net 66 "GND")
			(pinfunction "SH")
			(pintype "passive")
		)
	)
	(footprint "antmicro-footprints:R_0402_1005Metric"
		(layer "F.Cu")
		(at 148.736999 57.376001 -90)
		(descr "Resistor SMD 0402")
		(tags "resistor SMD 0402")
		(property "Reference" "R4"
			(at 1.773999 0.360998 90)
			(layer "F.SilkS")
			(effects
				(font
					(size 0.7 0.7)
					(thickness 0.15)
				)
				(justify right top)
			)
		)
		(property "Value" "R_1k_0402"
			(at -1.011843 1.772046 90)
			(layer "F.Fab")
			(effects
				(font
					(size 0.7 0.7)
					(thickness 0.15)
				)
				(justify right top)
			)
		)
		(property "Datasheet" "https://www.bourns.com/docs/product-datasheets/cr.pdf"
			(at 0 0 90)
			(layer "F.Fab")
			(hide yes)
			(effects
				(font
					(size 1.27 1.27)
					(thickness 0.15)
				)
			)
		)
		(property "Description" "SMD Chip Resistor, 1 kohm, ± 1%, 63 mW, 0402 [1005 Metric], Thick Film, General Purpose"
			(at 0 0 90)
			(layer "F.Fab")
			(hide yes)
			(effects
				(font
					(size 1.27 1.27)
					(thickness 0.15)
				)
			)
		)
		(property "MPN" "CR0402-FX-1001GLF"
			(at 0 0 270)
			(unlocked yes)
			(layer "F.Fab")
			(hide yes)
			(effects
				(font
					(size 1 1)
					(thickness 0.15)
				)
			)
		)
		(property "Manufacturer" "Bourns"
			(at 0 0 270)
			(unlocked yes)
			(layer "F.Fab")
			(hide yes)
			(effects
				(font
					(size 1 1)
					(thickness 0.15)
				)
			)
		)
		(property "License" "Apache-2.0"
			(at 0 0 270)
			(unlocked yes)
			(layer "F.Fab")
			(hide yes)
			(effects
				(font
					(size 1 1)
					(thickness 0.15)
				)
			)
		)
		(property "Author" "Antmicro"
			(at 0 0 270)
			(unlocked yes)
			(layer "F.Fab")
			(hide yes)
			(effects
				(font
					(size 1 1)
					(thickness 0.15)
				)
			)
		)
		(property "Val" "1k"
			(at 0 0 270)
			(unlocked yes)
			(layer "F.Fab")
			(hide yes)
			(effects
				(font
					(size 1 1)
					(thickness 0.15)
				)
			)
		)
		(property "Tolerance" "1%"
			(at 0 0 270)
			(unlocked yes)
			(layer "F.Fab")
			(hide yes)
			(effects
				(font
					(size 1 1)
					(thickness 0.15)
				)
			)
		)
		(sheetname "/USB-PD/")
		(sheetfile "usb-pd.kicad_sch")
		(attr smd)
		(fp_rect
			(start -0.925 -0.47)
			(end 0.925 0.47)
			(stroke
				(width 0.05)
				(type default)
			)
			(fill no)
			(layer "F.CrtYd")
		)
		(fp_rect
			(start -0.5 -0.25)
			(end 0.5 0.25)
			(stroke
				(width 0.15)
				(type solid)
			)
			(fill no)
			(layer "F.Fab")
		)
		(fp_text user "Author: Antmicro"
			(at -0.95 4.169 90)
			(layer "F.Fab")
			(effects
				(font
					(size 0.7 0.7)
					(thickness 0.15)
				)
				(justify right top)
			)
		)
		(fp_text user "${REFERENCE}"
			(at 0 0 90)
			(layer "F.Fab")
			(effects
				(font
					(size 0.7 0.7)
					(thickness 0.15)
				)
				(justify right top)
			)
		)
		(fp_text user "License: Apache-2.0"
			(at -0.949999 5.169 90)
			(layer "F.Fab")
			(effects
				(font
					(size 0.7 0.7)
					(thickness 0.15)
				)
				(justify right top)
			)
		)
		(pad "1" smd roundrect
			(at -0.48 0 270)
			(size 0.59 0.64)
			(layers "F.Cu" "F.Mask" "F.Paste")
			(roundrect_rratio 0.25)
			(net 136 "/USB-PD/VBUS_MAX")
			(pintype "passive")
		)
		(pad "2" smd roundrect
			(at 0.48 0 270)
			(size 0.59 0.64)
			(layers "F.Cu" "F.Mask" "F.Paste")
			(roundrect_rratio 0.25)
			(net 117 "/USB-PD/VDDD_3V3")
			(pintype "passive")
		)
	)
	(footprint "antmicro-footprints:USON-10_2.5x1mm_P0.5mm"
		(layer "F.Cu")
		(at 134.6 47.001 -90)
		(descr "USON-10 2.5x1mm_ Pitch 0.5mm")
		(tags "USON-10 2.5x1mm Pitch 0.5mm")
		(property "Reference" "D13"
			(at 1.048002 -0.226933 180)
			(layer "F.SilkS")
			(effects
				(font
					(size 0.7 0.7)
					(thickness 0.15)
				)
				(justify right top)
			)
		)
		(property "Value" "ESD204DQAR"
			(at 0.018 2.499 90)
			(layer "F.Fab")
			(effects
				(font
					(size 0.7 0.7)
					(thickness 0.15)
				)
				(justify right top)
			)
		)
		(property "Datasheet" "https://www.ti.com/lit/ds/symlink/esd204.pdf?ts=1706004844383&ref_url=https%253A%252F%252Fwww.ti.com%252Finterface%252Fdiodes%252Fesd-protection-diodes%252Fproducts.html"
			(at 0 0 90)
			(layer "F.Fab")
			(hide yes)
			(effects
				(font
					(size 1.27 1.27)
					(thickness 0.15)
				)
			)
		)
		(property "Description" "TVS diode array, 30 kV, USON-10, 3.6 V, 0.55 pF"
			(at 0 0 90)
			(layer "F.Fab")
			(hide yes)
			(effects
				(font
					(size 1.27 1.27)
					(thickness 0.15)
				)
			)
		)
		(property "MPN" "ESD204DQAR"
			(at 0 0 270)
			(unlocked yes)
			(layer "F.Fab")
			(hide yes)
			(effects
				(font
					(size 1 1)
					(thickness 0.15)
				)
			)
		)
		(property "Manufacturer" "Texas Instruments"
			(at 0 0 270)
			(unlocked yes)
			(layer "F.Fab")
			(hide yes)
			(effects
				(font
					(size 1 1)
					(thickness 0.15)
				)
			)
		)
		(property "Author" "Antmicro"
			(at 0 0 270)
			(unlocked yes)
			(layer "F.Fab")
			(hide yes)
			(effects
				(font
					(size 1 1)
					(thickness 0.15)
				)
			)
		)
		(property "License" "Apache-2.0"
			(at 0 0 270)
			(unlocked yes)
			(layer "F.Fab")
			(hide yes)
			(effects
				(font
					(size 1 1)
					(thickness 0.15)
				)
			)
		)
		(sheetname "/OCuLink/")
		(sheetfile "oculink.kicad_sch")
		(attr smd)
		(fp_line
			(start 0.498 1.398)
			(end -0.5 1.398)
			(stroke
				(width 0.15)
				(type solid)
			)
			(layer "F.SilkS")
		)
		(fp_line
			(start 0.498 -1.401)
			(end -0.5 -1.401)
			(stroke
				(width 0.15)
				(type solid)
			)
			(layer "F.SilkS")
		)
		(fp_circle
			(center -0.68 -1.27)
			(end -0.63 -1.27)
			(stroke
				(width 0.15)
				(type solid)
			)
			(fill yes)
			(layer "F.SilkS")
		)
		(fp_rect
			(start -0.8 -1.5)
			(end 0.8 1.499)
			(stroke
				(width 0.05)
				(type solid)
			)
			(fill no)
			(layer "F.CrtYd")
		)
		(fp_line
			(start -0.5 1.249)
			(end 0.498 1.249)
			(stroke
				(width 0.15)
				(type solid)
			)
			(layer "F.Fab")
		)
		(fp_line
			(start -0.5 -1)
			(end -0.5 1.249)
			(stroke
				(width 0.15)
				(type solid)
			)
			(layer "F.Fab")
		)
		(fp_line
			(start -0.25 -1.25)
			(end -0.5 -1)
			(stroke
				(width 0.15)
				(type solid)
			)
			(layer "F.Fab")
		)
		(fp_line
			(start 0.498 -1.25)
			(end 0.498 1.249)
			(stroke
				(width 0.15)
				(type solid)
			)
			(layer "F.Fab")
		)
		(fp_line
			(start 0.498 -1.25)
			(end -0.25 -1.25)
			(stroke
				(width 0.15)
				(type solid)
			)
			(layer "F.Fab")
		)
		(fp_text user "${REFERENCE}"
			(at 0 -0.000501 90)
			(layer "F.Fab")
			(effects
				(font
					(size 0.7 0.7)
					(thickness 0.15)
				)
				(justify right top)
			)
		)
		(fp_text user "License: Apache-2.0"
			(at -0.802 6.9 90)
			(layer "F.Fab")
			(effects
				(font
					(size 0.7 0.7)
					(thickness 0.15)
				)
				(justify right top)
			)
		)
		(fp_text user "Author: Antmicro"
			(at -0.802 5.7 90)
			(layer "F.Fab")
			(effects
				(font
					(size 0.7 0.7)
					(thickness 0.15)
				)
				(justify right top)
			)
		)
		(pad "1" smd roundrect
			(at -0.387 -1 180)
			(size 0.25 0.55)
			(layers "F.Cu" "F.Mask" "F.Paste")
			(roundrect_rratio 0.25)
			(net 70 "/OCuLink/PCIe_{x4}.TX2+")
			(pintype "passive")
		)
		(pad "2" smd roundrect
			(at -0.387 -0.5 180)
			(size 0.25 0.55)
			(layers "F.Cu" "F.Mask" "F.Paste")
			(roundrect_rratio 0.25)
			(net 76 "/OCuLink/PCIe_{x4}.TX2-")
			(pintype "passive")
		)
		(pad "3" smd roundrect
			(at -0.387 0 180)
			(size 0.4 0.55)
			(layers "F.Cu" "F.Mask" "F.Paste")
			(roundrect_rratio 0.25)
			(net 66 "GND")
			(pintype "power_in")
		)
		(pad "4" smd roundrect
			(at -0.387 0.498 180)
			(size 0.25 0.55)
			(layers "F.Cu" "F.Mask" "F.Paste")
			(roundrect_rratio 0.25)
			(net 82 "/OCuLink/PCIe_{x4}.TX3+")
			(pintype "passive")
		)
		(pad "5" smd roundrect
			(at -0.387 0.998 180)
			(size 0.25 0.55)
			(layers "F.Cu" "F.Mask" "F.Paste")
			(roundrect_rratio 0.25)
			(net 80 "/OCuLink/PCIe_{x4}.TX3-")
			(pintype "passive")
		)
		(pad "6" smd roundrect
			(at 0.385 0.998 180)
			(size 0.25 0.55)
			(layers "F.Cu" "F.Mask" "F.Paste")
			(roundrect_rratio 0.25)
			(net 80 "/OCuLink/PCIe_{x4}.TX3-")
			(pintype "passive")
		)
		(pad "7" smd roundrect
			(at 0.385 0.498 180)
			(size 0.25 0.55)
			(layers "F.Cu" "F.Mask" "F.Paste")
			(roundrect_rratio 0.25)
			(net 82 "/OCuLink/PCIe_{x4}.TX3+")
			(pintype "passive")
		)
		(pad "8" smd roundrect
			(at 0.385 0 180)
			(size 0.4 0.55)
			(layers "F.Cu" "F.Mask" "F.Paste")
			(roundrect_rratio 0.25)
			(net 66 "GND")
			(pintype "passive")
		)
		(pad "9" smd roundrect
			(at 0.385 -0.5 180)
			(size 0.25 0.55)
			(layers "F.Cu" "F.Mask" "F.Paste")
			(roundrect_rratio 0.25)
			(net 76 "/OCuLink/PCIe_{x4}.TX2-")
			(pintype "passive")
		)
		(pad "10" smd roundrect
			(at 0.385 -1 180)
			(size 0.25 0.55)
			(layers "F.Cu" "F.Mask" "F.Paste")
			(roundrect_rratio 0.25)
			(net 70 "/OCuLink/PCIe_{x4}.TX2+")
			(pintype "passive")
		)
	)
)
